(kicad_pcb
	(version 20260206)
	(generator "pcbnew")
	(generator_version "10.0")
	(general
		(thickness 1.6)
		(legacy_teardrops no)
	)
	(paper "A4")
	(title_block
		(title "01162023_DA0F0TEBIF0_F0T_Expander_BD_F_brd_V02_OCP.brd")
		(comment 1 "Grand Teton / footprints 9451-9458 of 9728")
	)
	(layers
		(0 "F.Cu" signal "TOP")
		(4 "In1.Cu" signal "GND")
		(6 "In2.Cu" signal "VCC")
		(8 "In3.Cu" signal "VCC1")
		(10 "In4.Cu" signal "GND1")
		(12 "In5.Cu" signal "IN1")
		(14 "In6.Cu" signal "GND2")
		(16 "In7.Cu" signal "IN2")
		(18 "In8.Cu" signal "GND3")
		(20 "In9.Cu" signal "IN3")
		(22 "In10.Cu" signal "GND4")
		(24 "In11.Cu" signal "IN4")
		(26 "In12.Cu" signal "GND5")
		(28 "In13.Cu" signal "IN5")
		(30 "In14.Cu" signal "GND6")
		(32 "In15.Cu" signal "IN6")
		(34 "In16.Cu" signal "GND7")
		(2 "B.Cu" signal "BOTTOM")
		(9 "F.Adhes" user "F.Adhesive")
		(11 "B.Adhes" user "B.Adhesive")
		(13 "F.Paste" user "Package Geometry/Pastemask Top")
		(15 "B.Paste" user "Package Geometry/Pastemask Bottom")
		(5 "F.SilkS" user "Ref Des/Silkscreen Top")
		(7 "B.SilkS" user "Ref Des/Silkscreen Bottom")
		(1 "F.Mask" user "Board Geometry/Soldermask Top")
		(3 "B.Mask" user "Board Geometry/Soldermask Bottom")
		(17 "Dwgs.User" user "User.Drawings")
		(19 "Cmts.User" user "User.Comments")
		(21 "Eco1.User" user "User.Eco1")
		(23 "Eco2.User" user "User.Eco2")
		(25 "Edge.Cuts" user "Board Geometry/Outline")
		(27 "Margin" user)
		(31 "F.CrtYd" user "Package Geometry/Place Bound Top")
		(29 "B.CrtYd" user "Package Geometry/Place Bound Bottom")
		(35 "F.Fab" user "Ref Des/Assembly Top")
		(33 "B.Fab" user "Ref Des/Assembly Bottom")
	)
	(footprint ""
		(layer "B.Cu")
		(at 287.099756 -303.499774 -90)
		(property "Reference" "C3263"
			(at 0 0 90)
			(layer "B.SilkS")
			(hide yes)
			(effects
				(font
					(size 1.27 1.27)
				)
				(justify mirror)
			)
		)
		(property "Value" ""
			(at 0 0 90)
			(layer "B.Fab")
			(effects
				(font
					(size 1.27 1.27)
				)
				(justify mirror)
			)
		)
		(duplicate_pad_numbers_are_jumpers no)
		(fp_line
			(start -0.299974 0.150114)
			(end 0.299974 0.150114)
			(stroke
				(width 0.1)
				(type default)
			)
			(layer "B.Fab")
		)
		(fp_line
			(start 0.299974 0.150114)
			(end 0.299974 -0.150114)
			(stroke
				(width 0.1)
				(type default)
			)
			(layer "B.Fab")
		)
		(fp_line
			(start -0.299974 -0.150114)
			(end -0.299974 0.150114)
			(stroke
				(width 0.1)
				(type default)
			)
			(layer "B.Fab")
		)
		(fp_line
			(start 0.299974 -0.150114)
			(end -0.299974 -0.150114)
			(stroke
				(width 0.1)
				(type default)
			)
			(layer "B.Fab")
		)
		(pad "1" smd rect
			(at 0.2667 0 90)
			(size 0.3048 0.381)
			(layers "B.Cu" "B.Mask" "B.Paste")
			(net "P1V25_PEX2")
		)
		(pad "2" smd rect
			(at -0.2667 0 90)
			(size 0.3048 0.381)
			(layers "B.Cu" "B.Mask" "B.Paste")
			(net "GND")
		)
	)
	(footprint ""
		(layer "B.Cu")
		(at 420.508176 -300.174914 180)
		(property "Reference" "C3531"
			(at 0 0 0)
			(layer "B.SilkS")
			(hide yes)
			(effects
				(font
					(size 1.27 1.27)
				)
				(justify mirror)
			)
		)
		(property "Value" ""
			(at 0 0 0)
			(layer "B.Fab")
			(effects
				(font
					(size 1.27 1.27)
				)
				(justify mirror)
			)
		)
		(duplicate_pad_numbers_are_jumpers no)
		(fp_line
			(start 0.299974 0.150114)
			(end 0.299974 -0.150114)
			(stroke
				(width 0.1)
				(type default)
			)
			(layer "B.Fab")
		)
		(fp_line
			(start 0.299974 -0.150114)
			(end -0.299974 -0.150114)
			(stroke
				(width 0.1)
				(type default)
			)
			(layer "B.Fab")
		)
		(fp_line
			(start -0.299974 0.150114)
			(end 0.299974 0.150114)
			(stroke
				(width 0.1)
				(type default)
			)
			(layer "B.Fab")
		)
		(fp_line
			(start -0.299974 -0.150114)
			(end -0.299974 0.150114)
			(stroke
				(width 0.1)
				(type default)
			)
			(layer "B.Fab")
		)
		(pad "1" smd rect
			(at 0.2667 0)
			(size 0.3048 0.381)
			(layers "B.Cu" "B.Mask" "B.Paste")
			(net "P1V8_VDDA_PEX3")
		)
		(pad "2" smd rect
			(at -0.2667 0)
			(size 0.3048 0.381)
			(layers "B.Cu" "B.Mask" "B.Paste")
			(net "GND")
		)
	)
	(footprint ""
		(layer "B.Cu")
		(at 69.00418 -117.723666)
		(property "Reference" "C418"
			(at 0 0 0)
			(layer "B.SilkS")
			(hide yes)
			(effects
				(font
					(size 1.27 1.27)
				)
				(justify mirror)
			)
		)
		(property "Value" ""
			(at 0 0 0)
			(layer "B.Fab")
			(effects
				(font
					(size 1.27 1.27)
				)
				(justify mirror)
			)
		)
		(duplicate_pad_numbers_are_jumpers no)
		(fp_line
			(start -0.7874 -0.4064)
			(end -0.7874 0.4064)
			(stroke
				(width 0.1524)
				(type default)
			)
			(layer "B.SilkS")
		)
		(fp_line
			(start -0.7874 0.4064)
			(end 0.7874 0.4064)
			(stroke
				(width 0.1524)
				(type default)
			)
			(layer "B.SilkS")
		)
		(fp_line
			(start 0.7874 -0.4064)
			(end -0.7874 -0.4064)
			(stroke
				(width 0.1524)
				(type default)
			)
			(layer "B.SilkS")
		)
		(fp_line
			(start 0.7874 0.4064)
			(end 0.7874 -0.4064)
			(stroke
				(width 0.1524)
				(type default)
			)
			(layer "B.SilkS")
		)
		(fp_line
			(start -0.67945 -0.3048)
			(end -0.67945 0.3048)
			(stroke
				(width 0.1)
				(type default)
			)
			(layer "B.Fab")
		)
		(fp_line
			(start -0.67945 0.3048)
			(end -0.120396 0.3048)
			(stroke
				(width 0.1)
				(type default)
			)
			(layer "B.Fab")
		)
		(fp_line
			(start -0.12065 -0.3048)
			(end -0.67945 -0.3048)
			(stroke
				(width 0.1)
				(type default)
			)
			(layer "B.Fab")
		)
		(fp_line
			(start -0.12065 -0.2794)
			(end -0.12065 -0.3048)
			(stroke
				(width 0.1)
				(type default)
			)
			(layer "B.Fab")
		)
		(fp_line
			(start -0.120396 0.2794)
			(end 0.12065 0.2794)
			(stroke
				(width 0.1)
				(type default)
			)
			(layer "B.Fab")
		)
		(fp_line
			(start -0.120396 0.3048)
			(end -0.120396 0.2794)
			(stroke
				(width 0.1)
				(type default)
			)
			(layer "B.Fab")
		)
		(fp_line
			(start 0.12065 -0.305054)
			(end 0.12065 -0.2794)
			(stroke
				(width 0.1)
				(type default)
			)
			(layer "B.Fab")
		)
		(fp_line
			(start 0.12065 -0.2794)
			(end -0.12065 -0.2794)
			(stroke
				(width 0.1)
				(type default)
			)
			(layer "B.Fab")
		)
		(fp_line
			(start 0.12065 0.2794)
			(end 0.12065 0.3048)
			(stroke
				(width 0.1)
				(type default)
			)
			(layer "B.Fab")
		)
		(fp_line
			(start 0.12065 0.3048)
			(end 0.67945 0.3048)
			(stroke
				(width 0.1)
				(type default)
			)
			(layer "B.Fab")
		)
		(fp_line
			(start 0.67945 -0.305054)
			(end 0.12065 -0.305054)
			(stroke
				(width 0.1)
				(type default)
			)
			(layer "B.Fab")
		)
		(fp_line
			(start 0.67945 0.3048)
			(end 0.67945 -0.305054)
			(stroke
				(width 0.1)
				(type default)
			)
			(layer "B.Fab")
		)
		(pad "1" smd circle
			(at 0.40005 0 180)
			(size 0 0)
			(layers "B.Cu" "B.Mask" "B.Paste")
			(net "P3V3_AUX")
		)
		(pad "2" smd circle
			(at -0.40005 0 180)
			(size 0 0)
			(layers "B.Cu" "B.Mask" "B.Paste")
			(net "GND")
		)
	)
	(footprint ""
		(layer "B.Cu")
		(at 128.966214 -202.221846 180)
		(property "Reference" "C2591"
			(at 0 0 0)
			(layer "B.SilkS")
			(hide yes)
			(effects
				(font
					(size 1.27 1.27)
				)
				(justify mirror)
			)
		)
		(property "Value" ""
			(at 0 0 0)
			(layer "B.Fab")
			(effects
				(font
					(size 1.27 1.27)
				)
				(justify mirror)
			)
		)
		(duplicate_pad_numbers_are_jumpers no)
		(fp_line
			(start 0.7874 0.4064)
			(end 0.7874 -0.4064)
			(stroke
				(width 0.1524)
				(type default)
			)
			(layer "B.SilkS")
		)
		(fp_line
			(start 0.7874 -0.4064)
			(end -0.7874 -0.4064)
			(stroke
				(width 0.1524)
				(type default)
			)
			(layer "B.SilkS")
		)
		(fp_line
			(start -0.7874 0.4064)
			(end 0.7874 0.4064)
			(stroke
				(width 0.1524)
				(type default)
			)
			(layer "B.SilkS")
		)
		(fp_line
			(start -0.7874 -0.4064)
			(end -0.7874 0.4064)
			(stroke
				(width 0.1524)
				(type default)
			)
			(layer "B.SilkS")
		)
		(fp_line
			(start 0.67945 0.3048)
			(end 0.67945 -0.305054)
			(stroke
				(width 0.1)
				(type default)
			)
			(layer "B.Fab")
		)
		(fp_line
			(start 0.67945 -0.305054)
			(end 0.12065 -0.305054)
			(stroke
				(width 0.1)
				(type default)
			)
			(layer "B.Fab")
		)
		(fp_line
			(start 0.12065 0.3048)
			(end 0.67945 0.3048)
			(stroke
				(width 0.1)
				(type default)
			)
			(layer "B.Fab")
		)
		(fp_line
			(start 0.12065 0.2794)
			(end 0.12065 0.3048)
			(stroke
				(width 0.1)
				(type default)
			)
			(layer "B.Fab")
		)
		(fp_line
			(start 0.12065 -0.2794)
			(end -0.12065 -0.2794)
			(stroke
				(width 0.1)
				(type default)
			)
			(layer "B.Fab")
		)
		(fp_line
			(start 0.12065 -0.305054)
			(end 0.12065 -0.2794)
			(stroke
				(width 0.1)
				(type default)
			)
			(layer "B.Fab")
		)
		(fp_line
			(start -0.120396 0.3048)
			(end -0.120396 0.2794)
			(stroke
				(width 0.1)
				(type default)
			)
			(layer "B.Fab")
		)
		(fp_line
			(start -0.120396 0.2794)
			(end 0.12065 0.2794)
			(stroke
				(width 0.1)
				(type default)
			)
			(layer "B.Fab")
		)
		(fp_line
			(start -0.12065 -0.2794)
			(end -0.12065 -0.3048)
			(stroke
				(width 0.1)
				(type default)
			)
			(layer "B.Fab")
		)
		(fp_line
			(start -0.12065 -0.3048)
			(end -0.67945 -0.3048)
			(stroke
				(width 0.1)
				(type default)
			)
			(layer "B.Fab")
		)
		(fp_line
			(start -0.67945 0.3048)
			(end -0.120396 0.3048)
			(stroke
				(width 0.1)
				(type default)
			)
			(layer "B.Fab")
		)
		(fp_line
			(start -0.67945 -0.3048)
			(end -0.67945 0.3048)
			(stroke
				(width 0.1)
				(type default)
			)
			(layer "B.Fab")
		)
		(pad "1" smd circle
			(at 0.40005 0)
			(size 0 0)
			(layers "B.Cu" "B.Mask" "B.Paste")
			(net "P3V3_AUX")
		)
		(pad "2" smd circle
			(at -0.40005 0)
			(size 0 0)
			(layers "B.Cu" "B.Mask" "B.Paste")
			(net "GND")
		)
	)
	(footprint ""
		(layer "B.Cu")
		(at 229.867714 -221.904052 90)
		(property "Reference" "C2014"
			(at 0 0 90)
			(layer "B.SilkS")
			(hide yes)
			(effects
				(font
					(size 1.27 1.27)
				)
				(justify mirror)
			)
		)
		(property "Value" ""
			(at 0 0 90)
			(layer "B.Fab")
			(effects
				(font
					(size 1.27 1.27)
				)
				(justify mirror)
			)
		)
		(duplicate_pad_numbers_are_jumpers no)
		(fp_line
			(start 0.69215 -0.2921)
			(end -0.69215 -0.2921)
			(stroke
				(width 0.1524)
				(type default)
			)
			(layer "B.SilkS")
		)
		(fp_line
			(start -0.69215 -0.2921)
			(end -0.69215 0.2921)
			(stroke
				(width 0.1524)
				(type default)
			)
			(layer "B.SilkS")
		)
		(fp_line
			(start 0.69215 0.2921)
			(end 0.69215 -0.2921)
			(stroke
				(width 0.1524)
				(type default)
			)
			(layer "B.SilkS")
		)
		(fp_line
			(start -0.69215 0.2921)
			(end 0.69215 0.2921)
			(stroke
				(width 0.1524)
				(type default)
			)
			(layer "B.SilkS")
		)
		(fp_line
			(start 0.51435 -0.2794)
			(end -0.51435 -0.2794)
			(stroke
				(width 0.1)
				(type default)
			)
			(layer "B.Fab")
		)
		(fp_line
			(start -0.51435 -0.2794)
			(end -0.51435 0.2794)
			(stroke
				(width 0.1)
				(type default)
			)
			(layer "B.Fab")
		)
		(fp_line
			(start 0.51435 0.2794)
			(end 0.51435 -0.2794)
			(stroke
				(width 0.1)
				(type default)
			)
			(layer "B.Fab")
		)
		(fp_line
			(start -0.51435 0.2794)
			(end 0.51435 0.2794)
			(stroke
				(width 0.1)
				(type default)
			)
			(layer "B.Fab")
		)
		(pad "1" smd circle
			(at 0.40005 0 270)
			(size 0 0)
			(layers "B.Cu" "B.Mask" "B.Paste")
			(net "P1V2_AUX")
		)
		(pad "2" smd circle
			(at -0.40005 0 270)
			(size 0 0)
			(layers "B.Cu" "B.Mask" "B.Paste")
			(net "GND")
		)
		(zone
			(layer "B.Cu")
			(hatch none 0.5)
			(connect_pads
				(clearance 0)
			)
			(min_thickness 0.25)
			(keepout
				(tracks not_allowed)
				(vias allowed)
				(pads allowed)
				(copperpour not_allowed)
				(footprints allowed)
			)
			(placement
				(enabled no)
				(sheetname "")
			)
			(fill
				(thermal_gap 0.5)
				(thermal_bridge_width 0.5)
				(island_removal_mode 0)
			)
			(polygon
				(pts
					(xy 229.955344 -222.094552) (xy 230.01351 -222.003112) (xy 230.01351 -221.803722) (xy 229.955344 -221.713552)
					(xy 229.780084 -221.713552) (xy 229.721664 -221.803722) (xy 229.721664 -222.003112) (xy 229.77983 -222.094552)
				)
			)
		)
	)
	(footprint ""
		(layer "B.Cu")
		(at 358.747568 -325.338948 -90)
		(property "Reference" "C4368"
			(at 0 0 90)
			(layer "B.SilkS")
			(hide yes)
			(effects
				(font
					(size 1.27 1.27)
				)
				(justify mirror)
			)
		)
		(property "Value" ""
			(at 0 0 90)
			(layer "B.Fab")
			(effects
				(font
					(size 1.27 1.27)
				)
				(justify mirror)
			)
		)
		(duplicate_pad_numbers_are_jumpers no)
		(fp_line
			(start -1.2954 0.5842)
			(end 1.2954 0.5842)
			(stroke
				(width 0.1524)
				(type default)
			)
			(layer "B.SilkS")
		)
		(fp_line
			(start 1.2954 0.5842)
			(end 1.2954 -0.5842)
			(stroke
				(width 0.1524)
				(type default)
			)
			(layer "B.SilkS")
		)
		(fp_line
			(start -1.2954 -0.5842)
			(end -1.2954 0.5842)
			(stroke
				(width 0.1524)
				(type default)
			)
			(layer "B.SilkS")
		)
		(fp_line
			(start 1.2954 -0.5842)
			(end -1.2954 -0.5842)
			(stroke
				(width 0.1524)
				(type default)
			)
			(layer "B.SilkS")
		)
		(fp_line
			(start -0.8636 0.4572)
			(end 0.8636 0.4572)
			(stroke
				(width 0.1)
				(type default)
			)
			(layer "B.Fab")
		)
		(fp_line
			(start 0.8636 0.4572)
			(end 0.8636 0.4064)
			(stroke
				(width 0.1)
				(type default)
			)
			(layer "B.Fab")
		)
		(fp_line
			(start -1.1938 0.4064)
			(end -0.8636 0.4064)
			(stroke
				(width 0.1)
				(type default)
			)
			(layer "B.Fab")
		)
		(fp_line
			(start -0.8636 0.4064)
			(end -0.8636 0.4572)
			(stroke
				(width 0.1)
				(type default)
			)
			(layer "B.Fab")
		)
		(fp_line
			(start 0.8636 0.4064)
			(end 1.1938 0.4064)
			(stroke
				(width 0.1)
				(type default)
			)
			(layer "B.Fab")
		)
		(fp_line
			(start 1.1938 0.4064)
			(end 1.1938 -0.4064)
			(stroke
				(width 0.1)
				(type default)
			)
			(layer "B.Fab")
		)
		(fp_line
			(start -1.1938 -0.4064)
			(end -1.1938 0.4064)
			(stroke
				(width 0.1)
				(type default)
			)
			(layer "B.Fab")
		)
		(fp_line
			(start -0.8636 -0.4064)
			(end -1.1938 -0.4064)
			(stroke
				(width 0.1)
				(type default)
			)
			(layer "B.Fab")
		)
		(fp_line
			(start 0.8636 -0.4064)
			(end 0.8636 -0.4572)
			(stroke
				(width 0.1)
				(type default)
			)
			(layer "B.Fab")
		)
		(fp_line
			(start 1.1938 -0.4064)
			(end 0.8636 -0.4064)
			(stroke
				(width 0.1)
				(type default)
			)
			(layer "B.Fab")
		)
		(fp_line
			(start -0.8636 -0.4572)
			(end -0.8636 -0.4064)
			(stroke
				(width 0.1)
				(type default)
			)
			(layer "B.Fab")
		)
		(fp_line
			(start 0.8636 -0.4572)
			(end -0.8636 -0.4572)
			(stroke
				(width 0.1)
				(type default)
			)
			(layer "B.Fab")
		)
		(pad "1" smd rect
			(at 0.7366 0 180)
			(size 0.7112 0.8128)
			(layers "B.Cu" "B.Mask" "B.Paste")
			(net "P0V8_SERDES_VDDA_PEX3_C2")
		)
		(pad "2" smd rect
			(at -0.7366 0 180)
			(size 0.7112 0.8128)
			(layers "B.Cu" "B.Mask" "B.Paste")
			(net "GND")
		)
	)
	(footprint ""
		(layer "B.Cu")
		(at 163.874958 -292.9636 90)
		(property "Reference" "C3220"
			(at 0 0 90)
			(layer "B.SilkS")
			(hide yes)
			(effects
				(font
					(size 1.27 1.27)
				)
				(justify mirror)
			)
		)
		(property "Value" ""
			(at 0 0 90)
			(layer "B.Fab")
			(effects
				(font
					(size 1.27 1.27)
				)
				(justify mirror)
			)
		)
		(duplicate_pad_numbers_are_jumpers no)
		(fp_line
			(start 0.299974 -0.150114)
			(end -0.299974 -0.150114)
			(stroke
				(width 0.1)
				(type default)
			)
			(layer "B.Fab")
		)
		(fp_line
			(start -0.299974 -0.150114)
			(end -0.299974 0.150114)
			(stroke
				(width 0.1)
				(type default)
			)
			(layer "B.Fab")
		)
		(fp_line
			(start 0.299974 0.150114)
			(end 0.299974 -0.150114)
			(stroke
				(width 0.1)
				(type default)
			)
			(layer "B.Fab")
		)
		(fp_line
			(start -0.299974 0.150114)
			(end 0.299974 0.150114)
			(stroke
				(width 0.1)
				(type default)
			)
			(layer "B.Fab")
		)
		(pad "1" smd rect
			(at 0.2667 0 270)
			(size 0.3048 0.381)
			(layers "B.Cu" "B.Mask" "B.Paste")
			(net "PCEPLL5_VDDA18_PEX1")
		)
		(pad "2" smd rect
			(at -0.2667 0 270)
			(size 0.3048 0.381)
			(layers "B.Cu" "B.Mask" "B.Paste")
			(net "GND")
		)
	)
	(footprint ""
		(layer "B.Cu")
		(at 109.641894 -321.810888 -90)
		(property "Reference" "R6457"
			(at 0 0 90)
			(layer "B.SilkS")
			(hide yes)
			(effects
				(font
					(size 1.27 1.27)
				)
				(justify mirror)
			)
		)
		(property "Value" ""
			(at 0 0 90)
			(layer "B.Fab")
			(effects
				(font
					(size 1.27 1.27)
				)
				(justify mirror)
			)
		)
		(duplicate_pad_numbers_are_jumpers no)
		(fp_line
			(start -0.7874 0.4064)
			(end 0.7874 0.4064)
			(stroke
				(width 0.1524)
				(type default)
			)
			(layer "B.SilkS")
		)
		(fp_line
			(start 0.7874 0.4064)
			(end 0.7874 -0.4064)
			(stroke
				(width 0.1524)
				(type default)
			)
			(layer "B.SilkS")
		)
		(fp_line
			(start -0.7874 -0.4064)
			(end -0.7874 0.4064)
			(stroke
				(width 0.1524)
				(type default)
			)
			(layer "B.SilkS")
		)
		(fp_line
			(start 0.7874 -0.4064)
			(end -0.7874 -0.4064)
			(stroke
				(width 0.1524)
				(type default)
			)
			(layer "B.SilkS")
		)
		(fp_line
			(start -0.67945 0.3048)
			(end -0.120396 0.3048)
			(stroke
				(width 0.1)
				(type default)
			)
			(layer "B.Fab")
		)
		(fp_line
			(start -0.120396 0.3048)
			(end -0.120396 0.2794)
			(stroke
				(width 0.1)
				(type default)
			)
			(layer "B.Fab")
		)
		(fp_line
			(start 0.12065 0.3048)
			(end 0.67945 0.3048)
			(stroke
				(width 0.1)
				(type default)
			)
			(layer "B.Fab")
		)
		(fp_line
			(start 0.67945 0.3048)
			(end 0.67945 -0.305054)
			(stroke
				(width 0.1)
				(type default)
			)
			(layer "B.Fab")
		)
		(fp_line
			(start -0.120396 0.2794)
			(end 0.12065 0.2794)
			(stroke
				(width 0.1)
				(type default)
			)
			(layer "B.Fab")
		)
		(fp_line
			(start 0.12065 0.2794)
			(end 0.12065 0.3048)
			(stroke
				(width 0.1)
				(type default)
			)
			(layer "B.Fab")
		)
		(fp_line
			(start -0.12065 -0.2794)
			(end -0.12065 -0.3048)
			(stroke
				(width 0.1)
				(type default)
			)
			(layer "B.Fab")
		)
		(fp_line
			(start 0.12065 -0.2794)
			(end -0.12065 -0.2794)
			(stroke
				(width 0.1)
				(type default)
			)
			(layer "B.Fab")
		)
		(fp_line
			(start -0.67945 -0.3048)
			(end -0.67945 0.3048)
			(stroke
				(width 0.1)
				(type default)
			)
			(layer "B.Fab")
		)
		(fp_line
			(start -0.12065 -0.3048)
			(end -0.67945 -0.3048)
			(stroke
				(width 0.1)
				(type default)
			)
			(layer "B.Fab")
		)
		(fp_line
			(start 0.12065 -0.305054)
			(end 0.12065 -0.2794)
			(stroke
				(width 0.1)
				(type default)
			)
			(layer "B.Fab")
		)
		(fp_line
			(start 0.67945 -0.305054)
			(end 0.12065 -0.305054)
			(stroke
				(width 0.1)
				(type default)
			)
			(layer "B.Fab")
		)
		(pad "1" smd circle
			(at 0.40005 0 90)
			(size 0 0)
			(layers "B.Cu" "B.Mask" "B.Paste")
			(net "P0V8_SERDES_VDDA_PEX0")
		)
		(pad "2" smd circle
			(at -0.40005 0 90)
			(size 0 0)
			(layers "B.Cu" "B.Mask" "B.Paste")
			(net "P0V8_SERDES_VDDA_PEX0_C8")
		)
	)
)
